# S9S_MB_2U (Grand Teton) — schematic netlist excerpt (pin names and nets, part order shuffled) for the footprints in the layout excerpt that follows; sources: Cadence DE-HDL packaged netlist, KiCad conversion of 03242023_DA0F0TMBIJ0_F0T_Motherboard_J_brd_V01_OCP.brd

J68  PICOPROBE_BXA  DELTA-L 4.0 EMPTY  pkg TRIANG_LAUNCH_3PXB  page 308
  \1_p\  = DELTA_L_85_5INCH_IN4_DP
  \2_n\  = DELTA_L_85_5INCH_IN4_DN
  \3_g\  = DELTA_L_GND_1

(kicad_pcb
	(version 20260206)
	(generator "pcbnew")
	(generator_version "10.0")
	(general
		(thickness 1.6)
		(legacy_teardrops no)
	)
	(paper "A4")
	(title_block
		(title "03242023_DA0F0TMBIJ0_F0T_Motherboard_J_brd_V01_OCP.brd")
		(comment 1 "Grand Teton / footprints 5120-5120 of 6105")
	)
	(layers
		(0 "F.Cu" signal "TOP")
		(4 "In1.Cu" signal "GND")
		(6 "In2.Cu" signal "IN1")
		(8 "In3.Cu" signal "GND1")
		(10 "In4.Cu" signal "IN2")
		(12 "In5.Cu" signal "GND2")
		(14 "In6.Cu" signal "IN3")
		(16 "In7.Cu" signal "GND3")
		(18 "In8.Cu" signal "VCC")
		(20 "In9.Cu" signal "VCC1")
		(22 "In10.Cu" signal "GND4")
		(24 "In11.Cu" signal "IN4")
		(26 "In12.Cu" signal "GND5")
		(28 "In13.Cu" signal "IN5")
		(30 "In14.Cu" signal "GND6")
		(32 "In15.Cu" signal "IN6")
		(34 "In16.Cu" signal "GND7")
		(2 "B.Cu" signal "BOTTOM")
		(9 "F.Adhes" user "F.Adhesive")
		(11 "B.Adhes" user "B.Adhesive")
		(13 "F.Paste" user "Package Geometry/Pastemask Top")
		(15 "B.Paste" user "Package Geometry/Pastemask Bottom")
		(5 "F.SilkS" user "Ref Des/Silkscreen Top")
		(7 "B.SilkS" user "Ref Des/Silkscreen Bottom")
		(1 "F.Mask" user "Board Geometry/Soldermask Top")
		(3 "B.Mask" user "Board Geometry/Soldermask Bottom")
		(17 "Dwgs.User" user "User.Drawings")
		(19 "Cmts.User" user "User.Comments")
		(21 "Eco1.User" user "User.Eco1")
		(23 "Eco2.User" user "User.Eco2")
		(25 "Edge.Cuts" user "Board Geometry/Outline")
		(27 "Margin" user)
		(31 "F.CrtYd" user "Package Geometry/Place Bound Top")
		(29 "B.CrtYd" user "Package Geometry/Place Bound Bottom")
		(35 "F.Fab" user "Ref Des/Assembly Top")
		(33 "B.Fab" user "Ref Des/Assembly Bottom")
	)
	(footprint ""
		(layer "B.Cu")
		(at 250.65482 -2.159)
		(property "Reference" "J68"
			(at 4.20751 1.143 270)
			(unlocked yes)
			(layer "B.SilkS")
			(effects
				(font
					(size 0.7874 0.5842)
					(thickness 0.1524)
				)
				(justify left mirror)
			)
		)
		(property "Value" ""
			(at 0 0 0)
			(layer "B.Fab")
			(effects
				(font
					(size 1.27 1.27)
				)
				(justify mirror)
			)
		)
		(duplicate_pad_numbers_are_jumpers no)
		(fp_line
			(start -1.2192 -2.1082)
			(end -1.2192 2.1082)
			(stroke
				(width 0.1524)
				(type default)
			)
			(layer "B.SilkS")
		)
		(fp_line
			(start -1.2192 2.1082)
			(end 1.2192 2.1082)
			(stroke
				(width 0.1524)
				(type default)
			)
			(layer "B.SilkS")
		)
		(fp_line
			(start 1.2192 -2.1082)
			(end -1.2192 -2.1082)
			(stroke
				(width 0.1524)
				(type default)
			)
			(layer "B.SilkS")
		)
		(fp_line
			(start 1.2192 2.1082)
			(end 1.2192 -2.1082)
			(stroke
				(width 0.1524)
				(type default)
			)
			(layer "B.SilkS")
		)
		(pad "" np_thru_hole circle
			(at -3.4671 -1.27 270)
			(size 1.0414 1.0414)
			(drill 1.0414)
			(layers "*.Cu" "*.Mask")
			(clearance 0.381)
			(thermal_gap 0.381)
		)
		(pad "" np_thru_hole circle
			(at -3.4671 1.27 270)
			(size 1.0414 1.0414)
			(drill 1.0414)
			(layers "*.Cu" "*.Mask")
			(clearance 0.381)
			(thermal_gap 0.381)
		)
		(pad "" np_thru_hole circle
			(at 2.8829 -1.27 270)
			(size 1.0414 1.0414)
			(drill 1.0414)
			(layers "*.Cu" "*.Mask")
			(clearance 0.381)
			(thermal_gap 0.381)
		)
		(pad "" np_thru_hole circle
			(at 2.8829 1.27 270)
			(size 1.0414 1.0414)
			(drill 1.0414)
			(layers "*.Cu" "*.Mask")
			(clearance 0.381)
			(thermal_gap 0.381)
		)
		(pad "1" smd rect
			(at -0.8255 -0.249936 270)
			(size 0.3048 0.508)
			(layers "B.Cu" "B.Mask" "B.Paste")
			(net "DELTA_L_85_5INCH_IN4_DP")
		)
		(pad "2" smd rect
			(at -0.8255 0.249936 270)
			(size 0.3048 0.508)
			(layers "B.Cu" "B.Mask" "B.Paste")
			(net "DELTA_L_85_5INCH_IN4_DN")
		)
		(pad "3" smd circle
			(at 0 0 180)
			(size 0 0)
			(layers "B.Cu" "B.Mask" "B.Paste")
			(net "DELTA_L_GND_1")
		)
		(zone
			(layers "F.Cu" "B.Cu" "In1.Cu" "In2.Cu" "In3.Cu" "In4.Cu" "In5.Cu" "In6.Cu"
				"In7.Cu" "In8.Cu" "In9.Cu" "In10.Cu" "In11.Cu" "In12.Cu" "In13.Cu" "In14.Cu"
				"In15.Cu" "In16.Cu"
			)
			(hatch none 0.5)
			(connect_pads
				(clearance 0)
			)
			(min_thickness 0.25)
			(keepout
				(tracks not_allowed)
				(vias allowed)
				(pads allowed)
				(copperpour not_allowed)
				(footprints allowed)
			)
			(placement
				(enabled no)
				(sheetname "")
			)
			(fill
				(thermal_gap 0.5)
				(thermal_bridge_width 0.5)
				(island_removal_mode 0)
			)
			(polygon
				(pts
					(arc
						(start 248.11482 -3.429)
						(mid 246.26062 -3.429)
						(end 248.11482 -3.429)
					)
				)
			)
		)
		(zone
			(layers "F.Cu" "B.Cu" "In1.Cu" "In2.Cu" "In3.Cu" "In4.Cu" "In5.Cu" "In6.Cu"
				"In7.Cu" "In8.Cu" "In9.Cu" "In10.Cu" "In11.Cu" "In12.Cu" "In13.Cu" "In14.Cu"
				"In15.Cu" "In16.Cu"
			)
			(hatch none 0.5)
			(connect_pads
				(clearance 0)
			)
			(min_thickness 0.25)
			(keepout
				(tracks not_allowed)
				(vias allowed)
				(pads allowed)
				(copperpour not_allowed)
				(footprints allowed)
			)
			(placement
				(enabled no)
				(sheetname "")
			)
			(fill
				(thermal_gap 0.5)
				(thermal_bridge_width 0.5)
				(island_removal_mode 0)
			)
			(polygon
				(pts
					(arc
						(start 248.11482 -0.889)
						(mid 246.26062 -0.889)
						(end 248.11482 -0.889)
					)
				)
			)
		)
		(zone
			(layers "F.Cu" "B.Cu" "In1.Cu" "In2.Cu" "In3.Cu" "In4.Cu" "In5.Cu" "In6.Cu"
				"In7.Cu" "In8.Cu" "In9.Cu" "In10.Cu" "In11.Cu" "In12.Cu" "In13.Cu" "In14.Cu"
				"In15.Cu" "In16.Cu"
			)
			(hatch none 0.5)
			(connect_pads
				(clearance 0)
			)
			(min_thickness 0.25)
			(keepout
				(tracks not_allowed)
				(vias allowed)
				(pads allowed)
				(copperpour not_allowed)
				(footprints allowed)
			)
			(placement
				(enabled no)
				(sheetname "")
			)
			(fill
				(thermal_gap 0.5)
				(thermal_bridge_width 0.5)
				(island_removal_mode 0)
			)
			(polygon
				(pts
					(arc
						(start 254.46482 -3.429)
						(mid 252.61062 -3.429)
						(end 254.46482 -3.429)
					)
				)
			)
		)
		(zone
			(layers "F.Cu" "B.Cu" "In1.Cu" "In2.Cu" "In3.Cu" "In4.Cu" "In5.Cu" "In6.Cu"
				"In7.Cu" "In8.Cu" "In9.Cu" "In10.Cu" "In11.Cu" "In12.Cu" "In13.Cu" "In14.Cu"
				"In15.Cu" "In16.Cu"
			)
			(hatch none 0.5)
			(connect_pads
				(clearance 0)
			)
			(min_thickness 0.25)
			(keepout
				(tracks not_allowed)
				(vias allowed)
				(pads allowed)
				(copperpour not_allowed)
				(footprints allowed)
			)
			(placement
				(enabled no)
				(sheetname "")
			)
			(fill
				(thermal_gap 0.5)
				(thermal_bridge_width 0.5)
				(island_removal_mode 0)
			)
			(polygon
				(pts
					(arc
						(start 254.46482 -0.889)
						(mid 252.61062 -0.889)
						(end 254.46482 -0.889)
					)
				)
			)
		)
		(zone
			(layer "B.Cu")
			(hatch none 0.5)
			(connect_pads
				(clearance 0)
			)
			(min_thickness 0.25)
			(keepout
				(tracks not_allowed)
				(vias allowed)
				(pads allowed)
				(copperpour not_allowed)
				(footprints allowed)
			)
			(placement
				(enabled no)
				(sheetname "")
			)
			(fill
				(thermal_gap 0.5)
				(thermal_bridge_width 0.5)
				(island_removal_mode 0)
			)
			(polygon
				(pts
					(xy 249.53722 -2.70764) (xy 249.53722 -2.612136) (xy 250.13412 -2.612136) (xy 250.13412 -2.205736)
					(xy 249.53722 -2.205736) (xy 249.53722 -2.112264) (xy 250.13412 -2.112264) (xy 250.13412 -1.705864)
					(xy 249.53722 -1.705864) (xy 249.53722 -1.61036) (xy 250.23572 -1.61036) (xy 250.23572 -2.70764)
				)
			)
		)
	)
)
